FILE_TYPE = CONNECTIVITY;
{Allegro Design Entry HDL 16.6-p007 (v16-6-112F) 10/10/2012}
"PAGE_NUMBER" = 94;
0"NC";
1"PVPP_ABC\g";
2"GND\g";
3"GND\g";
4"P3V3\g";
5"GND\g";
6"GND\g";
7"P3V3\g";
8"GND\g";
9"GND\g";
10"GND\g";
11"P3V3\g";
12"GND\g";
13"P3V3\g";
14"GND\g";
15"P3V3_STBY\g";
16"GND\g";
17"GND\g";
18"PVPP_ABC\g";
19"IRQ_PVDDQ_ABC_VRHOT_LVT3_N";
20"IRQ_PVDDQ_DEF_VRHOT_LVT3_N";
21"H_CPU0_MEMDEF_MEMHOT";
22"H_CPU0_MEMABC_MEMHOT";
23"H_CPU0_MEMDEF_MEMHOT_G_N";
24"H_CPU0_MEMABC_MEMHOT_G_N";
25"FM_DIMM_EVENT_COD_N";
26"IRQ_PVDDQ_KLM_VRHOT_LVT3_N";
27"IRQ_PVDDQ_GHJ_VRHOT_LVT3_N";
28"H_CPU1_MEMKLM_MEMHOT";
29"H_CPU1_MEMGHJ_MEMHOT";
30"FM_DIMM_EVENT_FET";
31"H_CPU1_MEMGHJ_MEMHOT_G_N";
32"H_CPU1_MEMKLM_MEMHOT_G_N";
33"FM_MEM_THERM_EVENT_LVT3_N";
%"RES"
"2","(-300,3650)","2","mstr_discrete","I100";
;
CDS_SEC"1"
ROOM"PROC_SIDEBAND"
CDS_LOCATION"R4U2"
SEC"1"
CDS_LIB"mstr_discrete"
BOM_COST"PROC_SIDEBAND"
SEC_TYPE"0402"
WATTAGE"1/16W"
MATERIAL"CHIP"
PACK_TYPE"0402"
TOLERANCE"1%"
VALUE"2.21K"
PART_NUMBER"G21796-112"
LOCATION"R4U2";
"A"
$PN"1"18;
"B"
$PN"2"25;
%"FET_N_DUAL"
"5","(1400,3950)","0","mstr_discrete","I102";
;
CDS_SEC"2"
ROOM"PROC_SIDEBAND"
CDS_LOCATION"Q4U1"
SEC"2"
BOM_COST"PROC_SIDEBAND"
CDS_LIB"mstr_discrete"
SEC_TYPE"SMLF"
PACK_TYPE"SMLF"
MATERIAL"FET"
VALUE"NTJD4001N"
PART_NUMBER"E40049-001"
LOCATION"Q4U1";
"GATE <SIZE -1..0>"
$PN"5"30;
"SOURCE <SIZE-1..0>"
$PN"4"16;
"DRAIN <SIZE -1..0>"
$PN"3"33;
%"PVPP_ABC"
"1","(175,4300)","0","mstr_symbols","I103";
;
HDL_POWER"PVPP_ABC"
ROOM"PVPP_KLM_VR"
BODY_TYPE"PLUMBING"
CDS_LIB"mstr_symbols"
BOM_COST"PVPP_KLM_VR"
VOLTAGE"2.5V";
"G\NAC"1;
%"RES"
"2","(750,3575)","0","mstr_discrete","I104";
;
CDS_SEC"1"
CDS_LOCATION"R4U4"
SEC"1"
SEC_TYPE"0402"
CDS_LIB"mstr_discrete"
WATTAGE"1/16W"
MATERIAL"CHIP"
PACK_TYPE"0402"
TOLERANCE"5%"
VALUE"33.0K"
PART_NUMBER"G21497-023"
LOCATION"R4U4";
"A"
$PN"1"30;
"B"
$PN"2"2;
%"GND"
"1","(750,3225)","0","mstr_symbols","I105";
;
HDL_POWER"GND"
BODY_TYPE"PLUMBING"
SIZE"1B"
CDS_LIB"mstr_symbols"
VOLTAGE"0";
"A\NAC"2;
%"GND"
"1","(-1425,1750)","0","mstr_symbols","I47";
;
HDL_POWER"GND"
ROOM"PROCHOT_MEMHOT_ISO"
BODY_TYPE"PLUMBING"
CDS_LIB"mstr_symbols"
SIZE"1B"
VOLTAGE"0";
"A\NAC"3;
%"FET_N_DUAL"
"5","(-2150,1925)","0","mstr_discrete","I49";
;
CDS_SEC"1"
ROOM"PROC_SIDEBAND"
CDS_LOCATION"Q3U1"
SEC"1"
SEC_TYPE"SMLF"
CDS_LIB"mstr_discrete"
PACK_TYPE"SMLF"
MATERIAL"FET"
VALUE"NTJD4001N"
PART_NUMBER"E40049-001"
LOCATION"Q3U1";
"GATE <SIZE -1..0>"
$PN"2"19;
"SOURCE <SIZE-1..0>"
$PN"1"5;
"DRAIN <SIZE -1..0>"
$PN"6"22;
%"P3V3"
"1","(-2150,2575)","0","mstr_symbols","I50";
;
HDL_POWER"P3V3"
ROOM"PROC_SIDEBAND"
BODY_TYPE"PLUMBING"
SIZE"1B"
CDS_LIB"mstr_symbols"
VOLTAGE"+3.3";
"G\NAC"4;
%"RES"
"2","(-2150,2375)","2","mstr_discrete","I51";
;
ROOM"PROC_SIDEBAND"
CDS_LOCATION"R7G7"
$SEC"1"
CDS_SEC"1"
BOM_COST"PROC_SIDEBAND"
CDS_LIB"mstr_discrete"
WATTAGE"1/16W"
MATERIAL"CHIP"
PACK_TYPE"0402"
TOLERANCE"1%"
VALUE"4.75K"
PART_NUMBER"G21796-072"
LOCATION"R7G7";
"A"
$PN"1"4;
"B"
$PN"2"22;
%"GND"
"1","(-2150,1650)","0","mstr_symbols","I56";
;
HDL_POWER"GND"
ROOM"PROCHOT_MEMHOT_ISO"
BODY_TYPE"PLUMBING"
CDS_LIB"mstr_symbols"
SIZE"1B"
VOLTAGE"0";
"A\NAC"5;
%"FET_N_DUAL"
"5","(-2150,825)","0","mstr_discrete","I60";
;
CDS_SEC"1"
ROOM"PROC_SIDEBAND"
CDS_LOCATION"Q7E1"
SEC"1"
SEC_TYPE"SMLF"
CDS_LIB"mstr_discrete"
PACK_TYPE"SMLF"
MATERIAL"FET"
VALUE"NTJD4001N"
PART_NUMBER"E40049-001"
LOCATION"Q7E1";
"GATE <SIZE -1..0>"
$PN"2"20;
"SOURCE <SIZE-1..0>"
$PN"1"8;
"DRAIN <SIZE -1..0>"
$PN"6"21;
%"GND"
"1","(-1425,650)","0","mstr_symbols","I63";
;
HDL_POWER"GND"
ROOM"PROCHOT_MEMHOT_ISO"
BODY_TYPE"PLUMBING"
CDS_LIB"mstr_symbols"
SIZE"1B"
VOLTAGE"0";
"A\NAC"6;
%"FET_N_DUAL"
"5","(-1425,950)","0","mstr_discrete","I64";
;
CDS_SEC"2"
ROOM"PROC_SIDEBAND"
CDS_LOCATION"Q7E1"
SEC"2"
SEC_TYPE"SMLF"
CDS_LIB"mstr_discrete"
PACK_TYPE"SMLF"
MATERIAL"FET"
VALUE"NTJD4001N"
PART_NUMBER"E40049-001"
LOCATION"Q7E1";
"GATE <SIZE -1..0>"
$PN"5"21;
"SOURCE <SIZE-1..0>"
$PN"4"6;
"DRAIN <SIZE -1..0>"
$PN"3"23;
%"P3V3"
"1","(-2150,1475)","0","mstr_symbols","I65";
;
HDL_POWER"P3V3"
ROOM"PROCHOT_MEMHOT_ISO"
BODY_TYPE"PLUMBING"
CDS_LIB"mstr_symbols"
SIZE"1B"
VOLTAGE"+3.3";
"G\NAC"7;
%"RES"
"2","(-2150,1275)","2","mstr_discrete","I66";
;
ROOM"PROC_SIDEBAND"
CDS_LOCATION"R3R4"
$SEC"1"
CDS_SEC"1"
BOM_COST"PROC_SIDEBAND"
CDS_LIB"mstr_discrete"
WATTAGE"1/16W"
MATERIAL"CHIP"
PACK_TYPE"0402"
TOLERANCE"1%"
VALUE"4.75K"
PART_NUMBER"G21796-072"
LOCATION"R3R4";
"A"
$PN"1"7;
"B"
$PN"2"21;
%"GND"
"1","(-2150,550)","0","mstr_symbols","I67";
;
HDL_POWER"GND"
ROOM"PROCHOT_MEMHOT_ISO"
BODY_TYPE"PLUMBING"
CDS_LIB"mstr_symbols"
SIZE"1B"
VOLTAGE"0";
"A\NAC"8;
%"FET_N_DUAL"
"5","(1175,1975)","0","mstr_discrete","I69";
;
CDS_SEC"1"
ROOM"PROC_SIDEBAND"
CDS_LOCATION"Q7E2"
SEC"1"
CDS_LIB"mstr_discrete"
SEC_TYPE"SMLF"
PACK_TYPE"SMLF"
MATERIAL"FET"
VALUE"NTJD4001N"
PART_NUMBER"E40049-001"
LOCATION"Q7E2";
"GATE <SIZE -1..0>"
$PN"2"27;
"SOURCE <SIZE-1..0>"
$PN"1"12;
"DRAIN <SIZE -1..0>"
$PN"6"29;
%"GND"
"1","(1900,1800)","0","mstr_symbols","I74";
;
HDL_POWER"GND"
ROOM"PROCHOT_MEMHOT_ISO"
BODY_TYPE"PLUMBING"
SIZE"1B"
CDS_LIB"mstr_symbols"
VOLTAGE"0";
"A\NAC"9;
%"FET_N_DUAL"
"5","(1900,2100)","0","mstr_discrete","I75";
;
CDS_SEC"2"
ROOM"PROC_SIDEBAND"
CDS_LOCATION"Q7E2"
SEC"2"
CDS_LIB"mstr_discrete"
SEC_TYPE"SMLF"
PACK_TYPE"SMLF"
MATERIAL"FET"
VALUE"NTJD4001N"
PART_NUMBER"E40049-001"
LOCATION"Q7E2";
"GATE <SIZE -1..0>"
$PN"5"29;
"SOURCE <SIZE-1..0>"
$PN"4"9;
"DRAIN <SIZE -1..0>"
$PN"3"31;
%"GND"
"1","(1900,700)","0","mstr_symbols","I76";
;
HDL_POWER"GND"
ROOM"PROCHOT_MEMHOT_ISO"
BODY_TYPE"PLUMBING"
SIZE"1B"
CDS_LIB"mstr_symbols"
VOLTAGE"0";
"A\NAC"10;
%"FET_N_DUAL"
"5","(1900,1000)","0","mstr_discrete","I77";
;
CDS_SEC"2"
ROOM"PROC_SIDEBAND"
CDS_LOCATION"Q4B1"
SEC"2"
CDS_LIB"mstr_discrete"
SEC_TYPE"SMLF"
PACK_TYPE"SMLF"
MATERIAL"FET"
VALUE"NTJD4001N"
PART_NUMBER"E40049-001"
LOCATION"Q4B1";
"GATE <SIZE -1..0>"
$PN"5"28;
"SOURCE <SIZE-1..0>"
$PN"4"10;
"DRAIN <SIZE -1..0>"
$PN"3"32;
%"P3V3"
"1","(1175,2625)","0","mstr_symbols","I78";
;
HDL_POWER"P3V3"
ROOM"PROCHOT_MEMHOT_ISO"
BODY_TYPE"PLUMBING"
SIZE"1B"
CDS_LIB"mstr_symbols"
VOLTAGE"+3.3";
"G\NAC"11;
%"RES"
"2","(1175,2425)","2","mstr_discrete","I79";
;
ROOM"PROC_SIDEBAND"
CDS_LOCATION"R3R10"
$SEC"1"
CDS_SEC"1"
CDS_LIB"mstr_discrete"
BOM_COST"PROC_SIDEBAND"
WATTAGE"1/16W"
MATERIAL"CHIP"
PACK_TYPE"0402"
TOLERANCE"1%"
VALUE"4.75K"
PART_NUMBER"G21796-072"
LOCATION"R3R10";
"A"
$PN"1"11;
"B"
$PN"2"29;
%"GND"
"1","(1175,1700)","0","mstr_symbols","I80";
;
HDL_POWER"GND"
ROOM"PROCHOT_MEMHOT_ISO"
BODY_TYPE"PLUMBING"
SIZE"1B"
CDS_LIB"mstr_symbols"
VOLTAGE"0";
"A\NAC"12;
%"P3V3"
"1","(1175,1525)","0","mstr_symbols","I81";
;
HDL_POWER"P3V3"
ROOM"PROCHOT_MEMHOT_ISO"
BODY_TYPE"PLUMBING"
SIZE"1B"
CDS_LIB"mstr_symbols"
VOLTAGE"+3.3";
"G\NAC"13;
%"RES"
"2","(1175,1325)","2","mstr_discrete","I82";
;
ROOM"PROC_SIDEBAND"
CDS_LOCATION"R6M4"
$SEC"1"
CDS_SEC"1"
CDS_LIB"mstr_discrete"
BOM_COST"PROC_SIDEBAND"
WATTAGE"1/16W"
MATERIAL"CHIP"
PACK_TYPE"0402"
TOLERANCE"1%"
VALUE"4.75K"
PART_NUMBER"G21796-072"
LOCATION"R6M4";
"A"
$PN"1"13;
"B"
$PN"2"28;
%"GND"
"1","(1175,600)","0","mstr_symbols","I83";
;
HDL_POWER"GND"
ROOM"PROCHOT_MEMHOT_ISO"
BODY_TYPE"PLUMBING"
SIZE"1B"
CDS_LIB"mstr_symbols"
VOLTAGE"0";
"A\NAC"14;
%"FET_N_DUAL"
"5","(1175,875)","0","mstr_discrete","I84";
;
CDS_SEC"1"
ROOM"PROC_SIDEBAND"
CDS_LOCATION"Q4B1"
SEC"1"
CDS_LIB"mstr_discrete"
SEC_TYPE"SMLF"
PACK_TYPE"SMLF"
MATERIAL"FET"
VALUE"NTJD4001N"
PART_NUMBER"E40049-001"
LOCATION"Q4B1";
"GATE <SIZE -1..0>"
$PN"2"26;
"SOURCE <SIZE-1..0>"
$PN"1"14;
"DRAIN <SIZE -1..0>"
$PN"6"28;
%"FET_N_DUAL"
"5","(-1425,2050)","0","mstr_discrete","I89";
;
CDS_SEC"2"
ROOM"PROC_SIDEBAND"
CDS_LOCATION"Q3U1"
SEC"2"
CDS_LIB"mstr_discrete"
SEC_TYPE"SMLF"
PACK_TYPE"SMLF"
MATERIAL"FET"
VALUE"NTJD4001N"
PART_NUMBER"E40049-001"
LOCATION"Q3U1";
"GATE <SIZE -1..0>"
$PN"5"22;
"SOURCE <SIZE-1..0>"
$PN"4"3;
"DRAIN <SIZE -1..0>"
$PN"3"24;
%"RES"
"2","(1400,4400)","2","mstr_discrete","I91";
;
CDS_SEC"1"
ROOM"PROC_SIDEBAND"
CDS_LOCATION"R4U1"
SEC"1"
SEC_TYPE"0402"
CDS_LIB"mstr_discrete"
BOM_COST"PROC_SIDEBAND"
WATTAGE"1/16W"
MATERIAL"CHIP"
PACK_TYPE"0402"
TOLERANCE"1%"
VALUE"4.75K"
PART_NUMBER"G21796-072"
LOCATION"R4U1";
"A"
$PN"1"15;
"B"
$PN"2"33;
%"P3V3_STBY"
"1","(1400,4700)","0","mstr_symbols","I92";
;
HDL_POWER"P3V3_STBY"
BODY_TYPE"PLUMBING"
CDS_LIB"mstr_symbols"
SIZE"1B"
VOLTAGE"3.3V";
"G\NAC"15;
%"RES"
"2","(175,4075)","2","mstr_discrete","I94";
;
CDS_SEC"1"
ROOM"PROC_SIDEBAND"
CDS_LOCATION"R4U3"
SEC"1"
CDS_LIB"mstr_discrete"
BOM_COST"PROC_SIDEBAND"
SEC_TYPE"0402"
WATTAGE"1/16W"
MATERIAL"CHIP"
PACK_TYPE"0402"
TOLERANCE"1%"
VALUE"4.75K"
PART_NUMBER"G21796-072"
LOCATION"R4U3";
"A"
$PN"1"1;
"B"
$PN"2"30;
%"GND"
"1","(1400,3550)","0","mstr_symbols","I95";
;
HDL_POWER"GND"
ROOM"SYSTEM_DEBUG_LEDS"
BODY_TYPE"PLUMBING"
BOM_COST"DEBUG"
SIZE"1B"
CDS_LIB"mstr_symbols"
VOLTAGE"0";
"A\NAC"16;
%"GND"
"1","(175,3225)","0","mstr_symbols","I97";
;
HDL_POWER"GND"
BODY_TYPE"PLUMBING"
CDS_LIB"mstr_symbols"
SIZE"1B"
VOLTAGE"0";
"A\NAC"17;
%"FET_N_DUAL"
"5","(175,3525)","0","mstr_discrete","I98";
;
CDS_SEC"1"
ROOM"PROC_SIDEBAND"
CDS_LOCATION"Q4U1"
SEC"1"
BOM_COST"PROC_SIDEBAND"
SEC_TYPE"SMLF"
CDS_LIB"mstr_discrete"
PACK_TYPE"SMLF"
MATERIAL"FET"
VALUE"NTJD4001N"
PART_NUMBER"E40049-001"
LOCATION"Q4U1";
"GATE <SIZE -1..0>"
$PN"2"25;
"SOURCE <SIZE-1..0>"
$PN"1"17;
"DRAIN <SIZE -1..0>"
$PN"6"30;
%"PVPP_ABC"
"1","(-300,4050)","0","mstr_symbols","I99";
;
HDL_POWER"PVPP_ABC"
ROOM"PVPP_KLM_VR"
BODY_TYPE"PLUMBING"
CDS_LIB"mstr_symbols"
BOM_COST"PVPP_KLM_VR"
VOLTAGE"2.5V";
"G\NAC"18;
END.
